(kicad_pcb
	(version 20260206)
	(generator "pcbnew")
	(generator_version "10.0")
	(general
		(thickness 1.6)
		(legacy_teardrops no)
	)
	(paper "A4")
	(title_block
		(title "Bryce Canyon_R.DPB_16317-1_OCP.brd")
		(comment 1 "Bryce Canyon / footprints 909-916 of 2099")
	)
	(layers
		(0 "F.Cu" signal "TOP")
		(4 "In1.Cu" signal "L2GND")
		(6 "In2.Cu" signal "L3")
		(8 "In3.Cu" signal "L4VCC")
		(10 "In4.Cu" signal "L5VCC")
		(12 "In5.Cu" signal "L6")
		(14 "In6.Cu" signal "L7GND")
		(2 "B.Cu" signal "BOTTOM")
		(9 "F.Adhes" user "F.Adhesive")
		(11 "B.Adhes" user "B.Adhesive")
		(13 "F.Paste" user "Package Geometry/Pastemask Top")
		(15 "B.Paste" user "Package Geometry/Pastemask Bottom")
		(5 "F.SilkS" user "Ref Des/Silkscreen Top")
		(7 "B.SilkS" user "Ref Des/Silkscreen Bottom")
		(1 "F.Mask" user "Board Geometry/Soldermask Top")
		(3 "B.Mask" user "Board Geometry/Soldermask Bottom")
		(17 "Dwgs.User" user "User.Drawings")
		(19 "Cmts.User" user "User.Comments")
		(21 "Eco1.User" user "User.Eco1")
		(23 "Eco2.User" user "User.Eco2")
		(25 "Edge.Cuts" user "Board Geometry/Outline")
		(27 "Margin" user)
		(31 "F.CrtYd" user "Package Geometry/Place Bound Top")
		(29 "B.CrtYd" user "Package Geometry/Place Bound Bottom")
		(35 "F.Fab" user "Ref Des/Assembly Top")
		(33 "B.Fab" user "Ref Des/Assembly Bottom")
	)
	(footprint ""
		(layer "F.Cu")
		(at 127.113284 -129.66065 90)
		(property "Reference" "C224"
			(at 0 0 90)
			(layer "F.SilkS")
			(hide yes)
			(effects
				(font
					(size 1.27 1.27)
				)
			)
		)
		(property "Value" "SCD01U16V1KX-GP"
			(at -2.8321 -1.7399 90)
			(unlocked yes)
			(layer "F.Fab")
			(hide yes)
			(effects
				(font
					(size 1.016 1.016)
					(thickness 0.1524)
				)
			)
		)
		(property "Device Type" "C0201H13"
			(at -2.8321 -3.2639 90)
			(unlocked yes)
			(layer "F.Fab")
			(hide yes)
			(effects
				(font
					(size 1.016 1.016)
					(thickness 0.1524)
				)
			)
		)
		(duplicate_pad_numbers_are_jumpers no)
		(fp_rect
			(start -0.2794 0.6477)
			(end 0.2794 -0.6477)
			(stroke
				(width 0)
				(type default)
			)
			(fill no)
			(layer "F.CrtYd")
		)
		(fp_rect
			(start -0.2794 0.6477)
			(end 0.2794 -0.6477)
			(stroke
				(width 0)
				(type default)
			)
			(fill no)
			(layer "F.Fab")
		)
		(pad "1" smd custom
			(at 0 -0.2794 90)
			(size 0.0762 0.0762)
			(layers "F.Cu" "F.Mask" "F.Paste")
			(net "SAS_HDD_RX_P15")
			(options
				(clearance outline)
				(anchor circle)
			)
			(primitives
				(gr_poly
					(pts
						(arc
							(start 0.1524 -0.127)
							(mid 0.137521 -0.162921)
							(end 0.1016 -0.1778)
						)
						(arc
							(start -0.1016 -0.1778)
							(mid -0.137521 -0.162921)
							(end -0.1524 -0.127)
						)
						(arc
							(start -0.1524 0.127)
							(mid -0.137521 0.162921)
							(end -0.1016 0.1778)
						)
						(arc
							(start 0.1016 0.1778)
							(mid 0.137521 0.162921)
							(end 0.1524 0.127)
						)
					)
					(width 0)
					(fill yes)
				)
			)
		)
		(pad "2" smd custom
			(at 0 0.2794 90)
			(size 0.0762 0.0762)
			(layers "F.Cu" "F.Mask" "F.Paste")
			(net "PHY_SCC_B_TO_DRV_B_15_DP")
			(options
				(clearance outline)
				(anchor circle)
			)
			(primitives
				(gr_poly
					(pts
						(arc
							(start 0.1524 -0.127)
							(mid 0.137521 -0.162921)
							(end 0.1016 -0.1778)
						)
						(arc
							(start -0.1016 -0.1778)
							(mid -0.137521 -0.162921)
							(end -0.1524 -0.127)
						)
						(arc
							(start -0.1524 0.127)
							(mid -0.137521 0.162921)
							(end -0.1016 0.1778)
						)
						(arc
							(start 0.1016 0.1778)
							(mid 0.137521 0.162921)
							(end 0.1524 0.127)
						)
					)
					(width 0)
					(fill yes)
				)
			)
		)
	)
	(footprint ""
		(layer "F.Cu")
		(at 430.403 -128.651 180)
		(property "Reference" "R564"
			(at 0 0 180)
			(layer "F.SilkS")
			(hide yes)
			(effects
				(font
					(size 1.27 1.27)
				)
			)
		)
		(property "Value" "0R2J-2-GP"
			(at 0.064008 -3.993896 180)
			(unlocked yes)
			(layer "F.Fab")
			(hide yes)
			(effects
				(font
					(size 1.016 1.016)
					(thickness 0.1524)
				)
			)
		)
		(property "Device Type" "R402H16"
			(at 0.064008 -5.517896 180)
			(unlocked yes)
			(layer "F.Fab")
			(hide yes)
			(effects
				(font
					(size 1.016 1.016)
					(thickness 0.1524)
				)
			)
		)
		(duplicate_pad_numbers_are_jumpers no)
		(fp_line
			(start 0.508 -0.9398)
			(end -0.508 -0.9398)
			(stroke
				(width 0.1524)
				(type default)
			)
			(layer "F.SilkS")
		)
		(fp_line
			(start -0.508 -0.9398)
			(end -0.508 0.9398)
			(stroke
				(width 0.1524)
				(type default)
			)
			(layer "F.SilkS")
		)
		(fp_rect
			(start -0.508 0.9398)
			(end 0.508 -0.9398)
			(stroke
				(width 0)
				(type default)
			)
			(fill no)
			(layer "F.CrtYd")
		)
		(fp_rect
			(start -0.508 0.9398)
			(end 0.508 -0.9398)
			(stroke
				(width 0)
				(type default)
			)
			(fill no)
			(layer "F.Fab")
		)
		(pad "1" smd custom
			(at 0 -0.4445 180)
			(size 0.1397 0.1397)
			(layers "F.Cu" "F.Mask" "F.Paste")
			(net "DRIVE_B_21_PWR")
			(options
				(clearance outline)
				(anchor circle)
			)
			(primitives
				(gr_poly
					(pts
						(arc
							(start -0.1778 -0.2794)
							(mid -0.249642 -0.249642)
							(end -0.2794 -0.1778)
						)
						(arc
							(start -0.2794 0.1778)
							(mid -0.249642 0.249642)
							(end -0.1778 0.2794)
						)
						(arc
							(start 0.1778 0.2794)
							(mid 0.249642 0.249642)
							(end 0.2794 0.1778)
						)
						(arc
							(start 0.2794 -0.1778)
							(mid 0.249642 -0.249642)
							(end 0.1778 -0.2794)
						)
					)
					(width 0)
					(fill yes)
				)
			)
		)
		(pad "2" smd custom
			(at 0 0.4445 180)
			(size 0.1397 0.1397)
			(layers "F.Cu" "F.Mask" "F.Paste")
			(net "SW_PWR_R_HDD21")
			(options
				(clearance outline)
				(anchor circle)
			)
			(primitives
				(gr_poly
					(pts
						(arc
							(start -0.1778 -0.2794)
							(mid -0.249642 -0.249642)
							(end -0.2794 -0.1778)
						)
						(arc
							(start -0.2794 0.1778)
							(mid -0.249642 0.249642)
							(end -0.1778 0.2794)
						)
						(arc
							(start 0.1778 0.2794)
							(mid 0.249642 0.249642)
							(end 0.2794 0.1778)
						)
						(arc
							(start 0.2794 -0.1778)
							(mid 0.249642 -0.249642)
							(end 0.1778 -0.2794)
						)
					)
					(width 0)
					(fill yes)
				)
			)
		)
	)
	(footprint ""
		(layer "F.Cu")
		(at 412.8516 -261.3406)
		(property "Reference" "R305"
			(at 0 0 0)
			(layer "F.SilkS")
			(hide yes)
			(effects
				(font
					(size 1.27 1.27)
				)
			)
		)
		(property "Value" "220R3F-1-GP"
			(at -0.0254 -2.5146 0)
			(unlocked yes)
			(layer "F.Fab")
			(hide yes)
			(effects
				(font
					(size 1.016 1.016)
					(thickness 0.1524)
				)
			)
		)
		(property "Device Type" "R603H22"
			(at -0.0254 -4.0386 0)
			(unlocked yes)
			(layer "F.Fab")
			(hide yes)
			(effects
				(font
					(size 1.016 1.016)
					(thickness 0.1524)
				)
			)
		)
		(duplicate_pad_numbers_are_jumpers no)
		(fp_line
			(start -0.4826 0)
			(end -0.2032 0)
			(stroke
				(width 0.2032)
				(type default)
			)
			(layer "F.SilkS")
		)
		(fp_line
			(start 0.2032 0)
			(end 0.4826 0)
			(stroke
				(width 0.2032)
				(type default)
			)
			(layer "F.SilkS")
		)
		(fp_rect
			(start -0.5842 1.3335)
			(end 0.5842 -1.3335)
			(stroke
				(width 0)
				(type default)
			)
			(fill no)
			(layer "F.CrtYd")
		)
		(fp_rect
			(start -0.5842 1.3335)
			(end 0.5842 -1.3335)
			(stroke
				(width 0)
				(type default)
			)
			(fill no)
			(layer "F.Fab")
		)
		(pad "1" smd custom
			(at 0 -0.762)
			(size 0.2159 0.2159)
			(layers "F.Cu" "F.Mask" "F.Paste")
			(net "HDD_PRSNT_9")
			(options
				(clearance outline)
				(anchor circle)
			)
			(primitives
				(gr_poly
					(pts
						(arc
							(start -0.3302 -0.4318)
							(mid -0.402042 -0.402042)
							(end -0.4318 -0.3302)
						)
						(arc
							(start -0.4318 0.3302)
							(mid -0.402042 0.402042)
							(end -0.3302 0.4318)
						)
						(arc
							(start 0.3302 0.4318)
							(mid 0.402042 0.402042)
							(end 0.4318 0.3302)
						)
						(arc
							(start 0.4318 -0.3302)
							(mid 0.402042 -0.402042)
							(end 0.3302 -0.4318)
						)
					)
					(width 0)
					(fill yes)
				)
			)
		)
		(pad "2" smd custom
			(at 0 0.762)
			(size 0.2159 0.2159)
			(layers "F.Cu" "F.Mask" "F.Paste")
			(net "DRIVE_B_9_INS")
			(options
				(clearance outline)
				(anchor circle)
			)
			(primitives
				(gr_poly
					(pts
						(arc
							(start -0.3302 -0.4318)
							(mid -0.402042 -0.402042)
							(end -0.4318 -0.3302)
						)
						(arc
							(start -0.4318 0.3302)
							(mid -0.402042 0.402042)
							(end -0.3302 0.4318)
						)
						(arc
							(start 0.3302 0.4318)
							(mid 0.402042 0.402042)
							(end 0.4318 0.3302)
						)
						(arc
							(start 0.4318 -0.3302)
							(mid 0.402042 -0.402042)
							(end 0.3302 -0.4318)
						)
					)
					(width 0)
					(fill yes)
				)
			)
		)
	)
	(footprint ""
		(layer "F.Cu")
		(at 176.149 -246.634)
		(property "Reference" "R251"
			(at 0 0 0)
			(layer "F.SilkS")
			(hide yes)
			(effects
				(font
					(size 1.27 1.27)
				)
			)
		)
		(property "Value" "0R2J-2-GP"
			(at 0.064008 -3.993896 0)
			(unlocked yes)
			(layer "F.Fab")
			(hide yes)
			(effects
				(font
					(size 1.016 1.016)
					(thickness 0.1524)
				)
			)
		)
		(property "Device Type" "R402H16"
			(at 0.064008 -5.517896 0)
			(unlocked yes)
			(layer "F.Fab")
			(hide yes)
			(effects
				(font
					(size 1.016 1.016)
					(thickness 0.1524)
				)
			)
		)
		(duplicate_pad_numbers_are_jumpers no)
		(fp_line
			(start -0.508 -0.9398)
			(end -0.508 0.9398)
			(stroke
				(width 0.1524)
				(type default)
			)
			(layer "F.SilkS")
		)
		(fp_line
			(start 0.508 -0.9398)
			(end -0.508 -0.9398)
			(stroke
				(width 0.1524)
				(type default)
			)
			(layer "F.SilkS")
		)
		(fp_rect
			(start -0.508 0.9398)
			(end 0.508 -0.9398)
			(stroke
				(width 0)
				(type default)
			)
			(fill no)
			(layer "F.CrtYd")
		)
		(fp_rect
			(start -0.508 0.9398)
			(end 0.508 -0.9398)
			(stroke
				(width 0)
				(type default)
			)
			(fill no)
			(layer "F.Fab")
		)
		(pad "1" smd custom
			(at 0 -0.4445)
			(size 0.1397 0.1397)
			(layers "F.Cu" "F.Mask" "F.Paste")
			(net "SW_HDD_G5")
			(options
				(clearance outline)
				(anchor circle)
			)
			(primitives
				(gr_poly
					(pts
						(arc
							(start -0.1778 -0.2794)
							(mid -0.249642 -0.249642)
							(end -0.2794 -0.1778)
						)
						(arc
							(start -0.2794 0.1778)
							(mid -0.249642 0.249642)
							(end -0.1778 0.2794)
						)
						(arc
							(start 0.1778 0.2794)
							(mid 0.249642 0.249642)
							(end 0.2794 0.1778)
						)
						(arc
							(start 0.2794 -0.1778)
							(mid 0.249642 -0.249642)
							(end 0.1778 -0.2794)
						)
					)
					(width 0)
					(fill yes)
				)
			)
		)
		(pad "2" smd custom
			(at 0 0.4445)
			(size 0.1397 0.1397)
			(layers "F.Cu" "F.Mask" "F.Paste")
			(net "SW_HDD_R5")
			(options
				(clearance outline)
				(anchor circle)
			)
			(primitives
				(gr_poly
					(pts
						(arc
							(start -0.1778 -0.2794)
							(mid -0.249642 -0.249642)
							(end -0.2794 -0.1778)
						)
						(arc
							(start -0.2794 0.1778)
							(mid -0.249642 0.249642)
							(end -0.1778 0.2794)
						)
						(arc
							(start 0.1778 0.2794)
							(mid 0.249642 0.249642)
							(end 0.2794 0.1778)
						)
						(arc
							(start 0.2794 -0.1778)
							(mid 0.249642 -0.249642)
							(end 0.1778 -0.2794)
						)
					)
					(width 0)
					(fill yes)
				)
			)
		)
	)
	(footprint ""
		(layer "F.Cu")
		(at 160.485582 -14.990826 90)
		(property "Reference" "VIA57"
			(at 0 0 90)
			(layer "F.SilkS")
			(hide yes)
			(effects
				(font
					(size 1.27 1.27)
				)
			)
		)
		(property "Value" "100OHM-8L-2D36MM-L18-GP"
			(at 3.8989 0.5715 90)
			(unlocked yes)
			(layer "F.Fab")
			(hide yes)
			(effects
				(font
					(size 1.016 1.016)
					(thickness 0.1524)
				)
			)
		)
		(property "Device Type" "VIA-PCIE-4P-414097"
			(at 3.8989 -0.9525 90)
			(unlocked yes)
			(layer "F.Fab")
			(hide yes)
			(effects
				(font
					(size 1.016 1.016)
					(thickness 0.1524)
				)
			)
		)
		(duplicate_pad_numbers_are_jumpers no)
		(fp_rect
			(start -2.0701 0.4826)
			(end 2.0701 -0.4826)
			(stroke
				(width 0)
				(type default)
			)
			(fill no)
			(layer "F.CrtYd")
		)
		(fp_rect
			(start -2.0701 0.4826)
			(end 2.0701 -0.4826)
			(stroke
				(width 0)
				(type default)
			)
			(fill no)
			(layer "F.Fab")
		)
		(pad "1" thru_hole circle
			(at -1.5875 0 90)
			(size 0.508 0.508)
			(drill 0.254)
			(layers "*.Cu" "*.Mask")
			(remove_unused_layers no)
			(net "GND")
			(clearance 0.2286)
			(thermal_gap 0.2286)
		)
		(pad "2" thru_hole circle
			(at -0.5715 0 90)
			(size 0.508 0.508)
			(drill 0.254)
			(layers "*.Cu" "*.Mask")
			(remove_unused_layers no)
			(net "PHY_SCC_B_TO_DRV_B_28_DP")
			(clearance 0.2286)
			(thermal_gap 0.2286)
		)
		(pad "3" thru_hole circle
			(at 0.5715 0 90)
			(size 0.508 0.508)
			(drill 0.254)
			(layers "*.Cu" "*.Mask")
			(remove_unused_layers no)
			(net "PHY_SCC_B_TO_DRV_B_28_DN")
			(clearance 0.2286)
			(thermal_gap 0.2286)
		)
		(pad "4" thru_hole circle
			(at 1.5875 0 90)
			(size 0.508 0.508)
			(drill 0.254)
			(layers "*.Cu" "*.Mask")
			(remove_unused_layers no)
			(net "GND")
			(clearance 0.2286)
			(thermal_gap 0.2286)
		)
	)
	(footprint ""
		(layer "F.Cu")
		(at 140.97 -150.622 -90)
		(property "Reference" "C241"
			(at 0 0 270)
			(layer "F.SilkS")
			(hide yes)
			(effects
				(font
					(size 1.27 1.27)
				)
			)
		)
		(property "Value" "SC4D7U25V5KX-1-GP"
			(at -0.0762 -6.1214 270)
			(unlocked yes)
			(layer "F.Fab")
			(hide yes)
			(effects
				(font
					(size 1.016 1.016)
					(thickness 0.1524)
				)
			)
		)
		(property "Device Type" "C805H58"
			(at -0.0762 -8.1534 270)
			(unlocked yes)
			(layer "F.Fab")
			(hide yes)
			(effects
				(font
					(size 1.016 1.016)
					(thickness 0.1524)
				)
			)
		)
		(duplicate_pad_numbers_are_jumpers no)
		(fp_line
			(start 0.635 0)
			(end -0.635 0)
			(stroke
				(width 0.508)
				(type default)
			)
			(layer "F.SilkS")
		)
		(fp_rect
			(start -0.9652 1.778)
			(end 0.9652 -1.778)
			(stroke
				(width 0)
				(type default)
			)
			(fill no)
			(layer "F.CrtYd")
		)
		(fp_poly
			(pts
				(xy -0.9652 -1.778) (xy 0.9652 -1.778) (xy 0.9652 1.778) (xy -0.9652 1.778)
			)
			(stroke
				(width 0)
				(type default)
			)
			(fill no)
			(layer "F.Fab")
		)
		(pad "1" smd rect
			(at 0 -0.9652 270)
			(size 1.397 1.143)
			(layers "F.Cu" "F.Mask" "F.Paste")
			(net "P12V_HDD16")
		)
		(pad "2" smd rect
			(at 0 0.9652 270)
			(size 1.397 1.143)
			(layers "F.Cu" "F.Mask" "F.Paste")
			(net "GND")
		)
	)
	(footprint ""
		(layer "F.Cu")
		(at 79.883 -139.065 -90)
		(property "Reference" "C220"
			(at 0 0 270)
			(layer "F.SilkS")
			(hide yes)
			(effects
				(font
					(size 1.27 1.27)
				)
			)
		)
		(property "Value" "SCD033U25V2KX-GP"
			(at 1.1811 -2.7051 270)
			(unlocked yes)
			(layer "F.Fab")
			(hide yes)
			(effects
				(font
					(size 1.016 1.016)
					(thickness 0.1524)
				)
			)
		)
		(property "Device Type" "C402H22"
			(at 1.1811 -4.2291 270)
			(unlocked yes)
			(layer "F.Fab")
			(hide yes)
			(effects
				(font
					(size 1.016 1.016)
					(thickness 0.1524)
				)
			)
		)
		(duplicate_pad_numbers_are_jumpers no)
		(fp_rect
			(start -0.4318 0.9525)
			(end 0.4318 -0.9525)
			(stroke
				(width 0)
				(type default)
			)
			(fill no)
			(layer "F.CrtYd")
		)
		(fp_rect
			(start -0.4318 0.9525)
			(end 0.4318 -0.9525)
			(stroke
				(width 0)
				(type default)
			)
			(fill no)
			(layer "F.Fab")
		)
		(pad "1" smd custom
			(at 0 -0.4445 270)
			(size 0.1524 0.1524)
			(layers "F.Cu" "F.Mask" "F.Paste")
			(net "SW_HDD_P14")
			(options
				(clearance outline)
				(anchor circle)
			)
			(primitives
				(gr_poly
					(pts
						(arc
							(start 0.3048 -0.2032)
							(mid 0.275042 -0.275042)
							(end 0.2032 -0.3048)
						)
						(arc
							(start -0.2032 -0.3048)
							(mid -0.275042 -0.275042)
							(end -0.3048 -0.2032)
						)
						(arc
							(start -0.3048 0.2032)
							(mid -0.275042 0.275042)
							(end -0.2032 0.3048)
						)
						(arc
							(start 0.2032 0.3048)
							(mid 0.275042 0.275042)
							(end 0.3048 0.2032)
						)
					)
					(width 0)
					(fill yes)
				)
			)
		)
		(pad "2" smd custom
			(at 0 0.4445 270)
			(size 0.1524 0.1524)
			(layers "F.Cu" "F.Mask" "F.Paste")
			(net "GND")
			(options
				(clearance outline)
				(anchor circle)
			)
			(primitives
				(gr_poly
					(pts
						(arc
							(start 0.3048 -0.2032)
							(mid 0.275042 -0.275042)
							(end 0.2032 -0.3048)
						)
						(arc
							(start -0.2032 -0.3048)
							(mid -0.275042 -0.275042)
							(end -0.3048 -0.2032)
						)
						(arc
							(start -0.3048 0.2032)
							(mid -0.275042 0.275042)
							(end -0.2032 0.3048)
						)
						(arc
							(start 0.2032 0.3048)
							(mid 0.275042 0.275042)
							(end 0.3048 0.2032)
						)
					)
					(width 0)
					(fill yes)
				)
			)
		)
	)
	(footprint ""
		(layer "F.Cu")
		(at 236.728 -222.377 90)
		(property "Reference" "R510"
			(at 0 0 90)
			(layer "F.SilkS")
			(hide yes)
			(effects
				(font
					(size 1.27 1.27)
				)
			)
		)
		(property "Value" "100KR2F-L1-GP"
			(at 0.064008 -3.993896 90)
			(unlocked yes)
			(layer "F.Fab")
			(hide yes)
			(effects
				(font
					(size 1.016 1.016)
					(thickness 0.1524)
				)
			)
		)
		(property "Device Type" "R402H16"
			(at 0.064008 -5.517896 90)
			(unlocked yes)
			(layer "F.Fab")
			(hide yes)
			(effects
				(font
					(size 1.016 1.016)
					(thickness 0.1524)
				)
			)
		)
		(duplicate_pad_numbers_are_jumpers no)
		(fp_line
			(start 0.508 -0.9398)
			(end -0.508 -0.9398)
			(stroke
				(width 0.1524)
				(type default)
			)
			(layer "F.SilkS")
		)
		(fp_line
			(start -0.508 -0.9398)
			(end -0.508 0.9398)
			(stroke
				(width 0.1524)
				(type default)
			)
			(layer "F.SilkS")
		)
		(fp_rect
			(start -0.508 0.9398)
			(end 0.508 -0.9398)
			(stroke
				(width 0)
				(type default)
			)
			(fill no)
			(layer "F.CrtYd")
		)
		(fp_rect
			(start -0.508 0.9398)
			(end 0.508 -0.9398)
			(stroke
				(width 0)
				(type default)
			)
			(fill no)
			(layer "F.Fab")
		)
		(pad "1" smd custom
			(at 0 -0.4445 90)
			(size 0.1397 0.1397)
			(layers "F.Cu" "F.Mask" "F.Paste")
			(net "GPIO_VCC_U8")
			(options
				(clearance outline)
				(anchor circle)
			)
			(primitives
				(gr_poly
					(pts
						(arc
							(start -0.1778 -0.2794)
							(mid -0.249642 -0.249642)
							(end -0.2794 -0.1778)
						)
						(arc
							(start -0.2794 0.1778)
							(mid -0.249642 0.249642)
							(end -0.1778 0.2794)
						)
						(arc
							(start 0.1778 0.2794)
							(mid 0.249642 0.249642)
							(end 0.2794 0.1778)
						)
						(arc
							(start 0.2794 -0.1778)
							(mid 0.249642 -0.249642)
							(end 0.1778 -0.2794)
						)
					)
					(width 0)
					(fill yes)
				)
			)
		)
		(pad "2" smd custom
			(at 0 0.4445 90)
			(size 0.1397 0.1397)
			(layers "F.Cu" "F.Mask" "F.Paste")
			(net "GND")
			(options
				(clearance outline)
				(anchor circle)
			)
			(primitives
				(gr_poly
					(pts
						(arc
							(start -0.1778 -0.2794)
							(mid -0.249642 -0.249642)
							(end -0.2794 -0.1778)
						)
						(arc
							(start -0.2794 0.1778)
							(mid -0.249642 0.249642)
							(end -0.1778 0.2794)
						)
						(arc
							(start 0.1778 0.2794)
							(mid 0.249642 0.249642)
							(end 0.2794 0.1778)
						)
						(arc
							(start 0.2794 -0.1778)
							(mid 0.249642 -0.249642)
							(end 0.1778 -0.2794)
						)
					)
					(width 0)
					(fill yes)
				)
			)
		)
	)
)
